(kicad_pcb
	(version 20260206)
	(generator "pcbnew")
	(generator_version "10.0")
	(general
		(thickness 1.6)
		(legacy_teardrops no)
	)
	(paper "A4")
	(title_block
		(title "04192023_DAF0TMB3IC0_F0TG_MB_C_brd_V02_OCP.brd")
		(comment 1 "Grand Teton / footprints 8083-8089 of 8354")
	)
	(layers
		(0 "F.Cu" signal "TOP")
		(4 "In1.Cu" signal "GND")
		(6 "In2.Cu" signal "IN1")
		(8 "In3.Cu" signal "GND1")
		(10 "In4.Cu" signal "IN2")
		(12 "In5.Cu" signal "GND2")
		(14 "In6.Cu" signal "IN3")
		(16 "In7.Cu" signal "GND3")
		(18 "In8.Cu" signal "VCC")
		(20 "In9.Cu" signal "VCC1")
		(22 "In10.Cu" signal "GND4")
		(24 "In11.Cu" signal "IN4")
		(26 "In12.Cu" signal "GND5")
		(28 "In13.Cu" signal "IN5")
		(30 "In14.Cu" signal "GND6")
		(32 "In15.Cu" signal "IN6")
		(34 "In16.Cu" signal "GND7")
		(2 "B.Cu" signal "BOTTOM")
		(9 "F.Adhes" user "F.Adhesive")
		(11 "B.Adhes" user "B.Adhesive")
		(13 "F.Paste" user "Package Geometry/Pastemask Top")
		(15 "B.Paste" user "Package Geometry/Pastemask Bottom")
		(5 "F.SilkS" user "Ref Des/Silkscreen Top")
		(7 "B.SilkS" user "Ref Des/Silkscreen Bottom")
		(1 "F.Mask" user "Board Geometry/Soldermask Top")
		(3 "B.Mask" user "Board Geometry/Soldermask Bottom")
		(17 "Dwgs.User" user "User.Drawings")
		(19 "Cmts.User" user "User.Comments")
		(21 "Eco1.User" user "User.Eco1")
		(23 "Eco2.User" user "User.Eco2")
		(25 "Edge.Cuts" user "Board Geometry/Outline")
		(27 "Margin" user)
		(31 "F.CrtYd" user "Package Geometry/Place Bound Top")
		(29 "B.CrtYd" user "Package Geometry/Place Bound Bottom")
		(35 "F.Fab" user "Ref Des/Assembly Top")
		(33 "B.Fab" user "Ref Des/Assembly Bottom")
	)
	(footprint ""
		(layer "B.Cu")
		(at 217.17 -332.74 180)
		(property "Reference" "R6776"
			(at 0 0 0)
			(layer "B.SilkS")
			(hide yes)
			(effects
				(font
					(size 1.27 1.27)
				)
				(justify mirror)
			)
		)
		(property "Value" ""
			(at 0 0 0)
			(layer "B.Fab")
			(effects
				(font
					(size 1.27 1.27)
				)
				(justify mirror)
			)
		)
		(duplicate_pad_numbers_are_jumpers no)
		(fp_line
			(start 0.32512 0.175006)
			(end 0.32512 -0.175006)
			(stroke
				(width 0.1)
				(type default)
			)
			(layer "B.Fab")
		)
		(fp_line
			(start 0.32512 -0.175006)
			(end -0.32512 -0.175006)
			(stroke
				(width 0.1)
				(type default)
			)
			(layer "B.Fab")
		)
		(fp_line
			(start -0.32512 0.175006)
			(end 0.32512 0.175006)
			(stroke
				(width 0.1)
				(type default)
			)
			(layer "B.Fab")
		)
		(fp_line
			(start -0.32512 -0.175006)
			(end -0.32512 0.175006)
			(stroke
				(width 0.1)
				(type default)
			)
			(layer "B.Fab")
		)
		(pad "1" smd rect
			(at 0.2667 0)
			(size 0.3048 0.381)
			(layers "B.Cu" "B.Mask" "B.Paste")
			(net "RST_SMB_RT_R1_N")
		)
		(pad "2" smd rect
			(at -0.2667 0 180)
			(size 0.3048 0.381)
			(layers "B.Cu" "B.Mask" "B.Paste")
			(net "RST_SMB_RT_N")
		)
	)
	(footprint ""
		(layer "B.Cu")
		(at 159.006286 -386.766562 90)
		(property "Reference" "C392"
			(at 0 0 90)
			(layer "B.SilkS")
			(hide yes)
			(effects
				(font
					(size 1.27 1.27)
				)
				(justify mirror)
			)
		)
		(property "Value" ""
			(at 0 0 90)
			(layer "B.Fab")
			(effects
				(font
					(size 1.27 1.27)
				)
				(justify mirror)
			)
		)
		(duplicate_pad_numbers_are_jumpers no)
		(fp_line
			(start 0.299974 -0.150114)
			(end -0.299974 -0.150114)
			(stroke
				(width 0.1)
				(type default)
			)
			(layer "B.Fab")
		)
		(fp_line
			(start -0.299974 -0.150114)
			(end -0.299974 0.150114)
			(stroke
				(width 0.1)
				(type default)
			)
			(layer "B.Fab")
		)
		(fp_line
			(start 0.299974 0.150114)
			(end 0.299974 -0.150114)
			(stroke
				(width 0.1)
				(type default)
			)
			(layer "B.Fab")
		)
		(fp_line
			(start -0.299974 0.150114)
			(end 0.299974 0.150114)
			(stroke
				(width 0.1)
				(type default)
			)
			(layer "B.Fab")
		)
		(pad "1" smd rect
			(at 0.2667 0 270)
			(size 0.3048 0.381)
			(layers "B.Cu" "B.Mask" "B.Paste")
			(net "P0V9_CPU1_RT_2D")
		)
		(pad "2" smd rect
			(at -0.2667 0 270)
			(size 0.3048 0.381)
			(layers "B.Cu" "B.Mask" "B.Paste")
			(net "GND")
		)
	)
	(footprint ""
		(layer "B.Cu")
		(at 96.842834 -306.701952 180)
		(property "Reference" "R1424"
			(at 0 0 0)
			(layer "B.SilkS")
			(hide yes)
			(effects
				(font
					(size 1.27 1.27)
				)
				(justify mirror)
			)
		)
		(property "Value" ""
			(at 0 0 0)
			(layer "B.Fab")
			(effects
				(font
					(size 1.27 1.27)
				)
				(justify mirror)
			)
		)
		(duplicate_pad_numbers_are_jumpers no)
		(fp_line
			(start 0.7874 0.4064)
			(end 0.7874 -0.4064)
			(stroke
				(width 0.1524)
				(type default)
			)
			(layer "B.SilkS")
		)
		(fp_line
			(start 0.7874 -0.4064)
			(end -0.7874 -0.4064)
			(stroke
				(width 0.1524)
				(type default)
			)
			(layer "B.SilkS")
		)
		(fp_line
			(start -0.7874 0.4064)
			(end 0.7874 0.4064)
			(stroke
				(width 0.1524)
				(type default)
			)
			(layer "B.SilkS")
		)
		(fp_line
			(start -0.7874 -0.4064)
			(end -0.7874 0.4064)
			(stroke
				(width 0.1524)
				(type default)
			)
			(layer "B.SilkS")
		)
		(fp_line
			(start 0.67945 0.3048)
			(end 0.67945 -0.305054)
			(stroke
				(width 0.1)
				(type default)
			)
			(layer "B.Fab")
		)
		(fp_line
			(start 0.67945 -0.305054)
			(end 0.12065 -0.305054)
			(stroke
				(width 0.1)
				(type default)
			)
			(layer "B.Fab")
		)
		(fp_line
			(start 0.12065 0.3048)
			(end 0.67945 0.3048)
			(stroke
				(width 0.1)
				(type default)
			)
			(layer "B.Fab")
		)
		(fp_line
			(start 0.12065 0.2794)
			(end 0.12065 0.3048)
			(stroke
				(width 0.1)
				(type default)
			)
			(layer "B.Fab")
		)
		(fp_line
			(start 0.12065 -0.2794)
			(end -0.12065 -0.2794)
			(stroke
				(width 0.1)
				(type default)
			)
			(layer "B.Fab")
		)
		(fp_line
			(start 0.12065 -0.305054)
			(end 0.12065 -0.2794)
			(stroke
				(width 0.1)
				(type default)
			)
			(layer "B.Fab")
		)
		(fp_line
			(start -0.120396 0.3048)
			(end -0.120396 0.2794)
			(stroke
				(width 0.1)
				(type default)
			)
			(layer "B.Fab")
		)
		(fp_line
			(start -0.120396 0.2794)
			(end 0.12065 0.2794)
			(stroke
				(width 0.1)
				(type default)
			)
			(layer "B.Fab")
		)
		(fp_line
			(start -0.12065 -0.2794)
			(end -0.12065 -0.3048)
			(stroke
				(width 0.1)
				(type default)
			)
			(layer "B.Fab")
		)
		(fp_line
			(start -0.12065 -0.3048)
			(end -0.67945 -0.3048)
			(stroke
				(width 0.1)
				(type default)
			)
			(layer "B.Fab")
		)
		(fp_line
			(start -0.67945 0.3048)
			(end -0.120396 0.3048)
			(stroke
				(width 0.1)
				(type default)
			)
			(layer "B.Fab")
		)
		(fp_line
			(start -0.67945 -0.3048)
			(end -0.67945 0.3048)
			(stroke
				(width 0.1)
				(type default)
			)
			(layer "B.Fab")
		)
		(pad "1" smd circle
			(at 0.40005 0)
			(size 0 0)
			(layers "B.Cu" "B.Mask" "B.Paste")
			(net "PVDD18_S5_P1")
		)
		(pad "2" smd circle
			(at -0.40005 0)
			(size 0 0)
			(layers "B.Cu" "B.Mask" "B.Paste")
			(net "INT_CPU1_HP_UBM_N")
		)
	)
	(footprint ""
		(layer "B.Cu")
		(at 84.811362 -336.037682 -90)
		(property "Reference" "PR256"
			(at 0 0 90)
			(layer "B.SilkS")
			(hide yes)
			(effects
				(font
					(size 1.27 1.27)
				)
				(justify mirror)
			)
		)
		(property "Value" ""
			(at 0 0 90)
			(layer "B.Fab")
			(effects
				(font
					(size 1.27 1.27)
				)
				(justify mirror)
			)
		)
		(duplicate_pad_numbers_are_jumpers no)
		(fp_line
			(start -0.7874 0.4064)
			(end 0.7874 0.4064)
			(stroke
				(width 0.1524)
				(type default)
			)
			(layer "B.SilkS")
		)
		(fp_line
			(start 0.7874 0.4064)
			(end 0.7874 -0.4064)
			(stroke
				(width 0.1524)
				(type default)
			)
			(layer "B.SilkS")
		)
		(fp_line
			(start -0.7874 -0.4064)
			(end -0.7874 0.4064)
			(stroke
				(width 0.1524)
				(type default)
			)
			(layer "B.SilkS")
		)
		(fp_line
			(start 0.7874 -0.4064)
			(end -0.7874 -0.4064)
			(stroke
				(width 0.1524)
				(type default)
			)
			(layer "B.SilkS")
		)
		(fp_line
			(start -0.67945 0.3048)
			(end -0.120396 0.3048)
			(stroke
				(width 0.1)
				(type default)
			)
			(layer "B.Fab")
		)
		(fp_line
			(start -0.120396 0.3048)
			(end -0.120396 0.2794)
			(stroke
				(width 0.1)
				(type default)
			)
			(layer "B.Fab")
		)
		(fp_line
			(start 0.12065 0.3048)
			(end 0.67945 0.3048)
			(stroke
				(width 0.1)
				(type default)
			)
			(layer "B.Fab")
		)
		(fp_line
			(start 0.67945 0.3048)
			(end 0.67945 -0.305054)
			(stroke
				(width 0.1)
				(type default)
			)
			(layer "B.Fab")
		)
		(fp_line
			(start -0.120396 0.2794)
			(end 0.12065 0.2794)
			(stroke
				(width 0.1)
				(type default)
			)
			(layer "B.Fab")
		)
		(fp_line
			(start 0.12065 0.2794)
			(end 0.12065 0.3048)
			(stroke
				(width 0.1)
				(type default)
			)
			(layer "B.Fab")
		)
		(fp_line
			(start -0.12065 -0.2794)
			(end -0.12065 -0.3048)
			(stroke
				(width 0.1)
				(type default)
			)
			(layer "B.Fab")
		)
		(fp_line
			(start 0.12065 -0.2794)
			(end -0.12065 -0.2794)
			(stroke
				(width 0.1)
				(type default)
			)
			(layer "B.Fab")
		)
		(fp_line
			(start -0.67945 -0.3048)
			(end -0.67945 0.3048)
			(stroke
				(width 0.1)
				(type default)
			)
			(layer "B.Fab")
		)
		(fp_line
			(start -0.12065 -0.3048)
			(end -0.67945 -0.3048)
			(stroke
				(width 0.1)
				(type default)
			)
			(layer "B.Fab")
		)
		(fp_line
			(start 0.12065 -0.305054)
			(end 0.12065 -0.2794)
			(stroke
				(width 0.1)
				(type default)
			)
			(layer "B.Fab")
		)
		(fp_line
			(start 0.67945 -0.305054)
			(end 0.12065 -0.305054)
			(stroke
				(width 0.1)
				(type default)
			)
			(layer "B.Fab")
		)
		(pad "1" smd circle
			(at 0.40005 0 90)
			(size 0 0)
			(layers "B.Cu" "B.Mask" "B.Paste")
			(net "PVDDCR_CPU1_P1_PVCC")
		)
		(pad "2" smd circle
			(at -0.40005 0 90)
			(size 0 0)
			(layers "B.Cu" "B.Mask" "B.Paste")
			(net "PVDDCR_CPU1_P1_VCC1")
		)
	)
	(footprint ""
		(layer "B.Cu")
		(at 420.407338 -172.290232 90)
		(property "Reference" "PR334"
			(at 0 0 90)
			(layer "B.SilkS")
			(hide yes)
			(effects
				(font
					(size 1.27 1.27)
				)
				(justify mirror)
			)
		)
		(property "Value" ""
			(at 0 0 90)
			(layer "B.Fab")
			(effects
				(font
					(size 1.27 1.27)
				)
				(justify mirror)
			)
		)
		(duplicate_pad_numbers_are_jumpers no)
		(fp_line
			(start 0.7874 -0.4064)
			(end -0.7874 -0.4064)
			(stroke
				(width 0.1524)
				(type default)
			)
			(layer "B.SilkS")
		)
		(fp_line
			(start -0.7874 -0.4064)
			(end -0.7874 0.4064)
			(stroke
				(width 0.1524)
				(type default)
			)
			(layer "B.SilkS")
		)
		(fp_line
			(start 0.7874 0.4064)
			(end 0.7874 -0.4064)
			(stroke
				(width 0.1524)
				(type default)
			)
			(layer "B.SilkS")
		)
		(fp_line
			(start -0.7874 0.4064)
			(end 0.7874 0.4064)
			(stroke
				(width 0.1524)
				(type default)
			)
			(layer "B.SilkS")
		)
		(fp_line
			(start 0.67945 -0.305054)
			(end 0.12065 -0.305054)
			(stroke
				(width 0.1)
				(type default)
			)
			(layer "B.Fab")
		)
		(fp_line
			(start 0.12065 -0.305054)
			(end 0.12065 -0.2794)
			(stroke
				(width 0.1)
				(type default)
			)
			(layer "B.Fab")
		)
		(fp_line
			(start -0.12065 -0.3048)
			(end -0.67945 -0.3048)
			(stroke
				(width 0.1)
				(type default)
			)
			(layer "B.Fab")
		)
		(fp_line
			(start -0.67945 -0.3048)
			(end -0.67945 0.3048)
			(stroke
				(width 0.1)
				(type default)
			)
			(layer "B.Fab")
		)
		(fp_line
			(start 0.12065 -0.2794)
			(end -0.12065 -0.2794)
			(stroke
				(width 0.1)
				(type default)
			)
			(layer "B.Fab")
		)
		(fp_line
			(start -0.12065 -0.2794)
			(end -0.12065 -0.3048)
			(stroke
				(width 0.1)
				(type default)
			)
			(layer "B.Fab")
		)
		(fp_line
			(start 0.12065 0.2794)
			(end 0.12065 0.3048)
			(stroke
				(width 0.1)
				(type default)
			)
			(layer "B.Fab")
		)
		(fp_line
			(start -0.120396 0.2794)
			(end 0.12065 0.2794)
			(stroke
				(width 0.1)
				(type default)
			)
			(layer "B.Fab")
		)
		(fp_line
			(start 0.67945 0.3048)
			(end 0.67945 -0.305054)
			(stroke
				(width 0.1)
				(type default)
			)
			(layer "B.Fab")
		)
		(fp_line
			(start 0.12065 0.3048)
			(end 0.67945 0.3048)
			(stroke
				(width 0.1)
				(type default)
			)
			(layer "B.Fab")
		)
		(fp_line
			(start -0.120396 0.3048)
			(end -0.120396 0.2794)
			(stroke
				(width 0.1)
				(type default)
			)
			(layer "B.Fab")
		)
		(fp_line
			(start -0.67945 0.3048)
			(end -0.120396 0.3048)
			(stroke
				(width 0.1)
				(type default)
			)
			(layer "B.Fab")
		)
		(pad "1" smd circle
			(at 0.40005 0 270)
			(size 0 0)
			(layers "B.Cu" "B.Mask" "B.Paste")
			(net "PVDDCR_SOC_P0")
		)
		(pad "2" smd circle
			(at -0.40005 0 270)
			(size 0 0)
			(layers "B.Cu" "B.Mask" "B.Paste")
			(net "GND")
		)
	)
	(footprint ""
		(layer "B.Cu")
		(at 162.73018 -20.056094 90)
		(property "Reference" "R6036"
			(at 0 0 90)
			(layer "B.SilkS")
			(hide yes)
			(effects
				(font
					(size 1.27 1.27)
				)
				(justify mirror)
			)
		)
		(property "Value" ""
			(at 0 0 90)
			(layer "B.Fab")
			(effects
				(font
					(size 1.27 1.27)
				)
				(justify mirror)
			)
		)
		(duplicate_pad_numbers_are_jumpers no)
		(fp_line
			(start 0.7874 -0.4064)
			(end -0.7874 -0.4064)
			(stroke
				(width 0.1524)
				(type default)
			)
			(layer "B.SilkS")
		)
		(fp_line
			(start -0.7874 -0.4064)
			(end -0.7874 0.4064)
			(stroke
				(width 0.1524)
				(type default)
			)
			(layer "B.SilkS")
		)
		(fp_line
			(start 0.7874 0.4064)
			(end 0.7874 -0.4064)
			(stroke
				(width 0.1524)
				(type default)
			)
			(layer "B.SilkS")
		)
		(fp_line
			(start -0.7874 0.4064)
			(end 0.7874 0.4064)
			(stroke
				(width 0.1524)
				(type default)
			)
			(layer "B.SilkS")
		)
		(fp_line
			(start 0.67945 -0.305054)
			(end 0.12065 -0.305054)
			(stroke
				(width 0.1)
				(type default)
			)
			(layer "B.Fab")
		)
		(fp_line
			(start 0.12065 -0.305054)
			(end 0.12065 -0.2794)
			(stroke
				(width 0.1)
				(type default)
			)
			(layer "B.Fab")
		)
		(fp_line
			(start -0.12065 -0.3048)
			(end -0.67945 -0.3048)
			(stroke
				(width 0.1)
				(type default)
			)
			(layer "B.Fab")
		)
		(fp_line
			(start -0.67945 -0.3048)
			(end -0.67945 0.3048)
			(stroke
				(width 0.1)
				(type default)
			)
			(layer "B.Fab")
		)
		(fp_line
			(start 0.12065 -0.2794)
			(end -0.12065 -0.2794)
			(stroke
				(width 0.1)
				(type default)
			)
			(layer "B.Fab")
		)
		(fp_line
			(start -0.12065 -0.2794)
			(end -0.12065 -0.3048)
			(stroke
				(width 0.1)
				(type default)
			)
			(layer "B.Fab")
		)
		(fp_line
			(start 0.12065 0.2794)
			(end 0.12065 0.3048)
			(stroke
				(width 0.1)
				(type default)
			)
			(layer "B.Fab")
		)
		(fp_line
			(start -0.120396 0.2794)
			(end 0.12065 0.2794)
			(stroke
				(width 0.1)
				(type default)
			)
			(layer "B.Fab")
		)
		(fp_line
			(start 0.67945 0.3048)
			(end 0.67945 -0.305054)
			(stroke
				(width 0.1)
				(type default)
			)
			(layer "B.Fab")
		)
		(fp_line
			(start 0.12065 0.3048)
			(end 0.67945 0.3048)
			(stroke
				(width 0.1)
				(type default)
			)
			(layer "B.Fab")
		)
		(fp_line
			(start -0.120396 0.3048)
			(end -0.120396 0.2794)
			(stroke
				(width 0.1)
				(type default)
			)
			(layer "B.Fab")
		)
		(fp_line
			(start -0.67945 0.3048)
			(end -0.120396 0.3048)
			(stroke
				(width 0.1)
				(type default)
			)
			(layer "B.Fab")
		)
		(pad "1" smd circle
			(at 0.40005 0 270)
			(size 0 0)
			(layers "B.Cu" "B.Mask" "B.Paste")
			(net "SMB_1_PLD_3V3AUX_SCL")
		)
		(pad "2" smd circle
			(at -0.40005 0 270)
			(size 0 0)
			(layers "B.Cu" "B.Mask" "B.Paste")
			(net "P3V3_AUX")
		)
	)
	(footprint ""
		(layer "B.Cu")
		(at 213.253066 -325.456296)
		(property "Reference" "C1094"
			(at 0 0 0)
			(layer "B.SilkS")
			(hide yes)
			(effects
				(font
					(size 1.27 1.27)
				)
				(justify mirror)
			)
		)
		(property "Value" ""
			(at 0 0 0)
			(layer "B.Fab")
			(effects
				(font
					(size 1.27 1.27)
				)
				(justify mirror)
			)
		)
		(duplicate_pad_numbers_are_jumpers no)
		(fp_line
			(start -0.7874 -0.4064)
			(end -0.7874 0.4064)
			(stroke
				(width 0.1524)
				(type default)
			)
			(layer "B.SilkS")
		)
		(fp_line
			(start -0.7874 0.4064)
			(end 0.7874 0.4064)
			(stroke
				(width 0.1524)
				(type default)
			)
			(layer "B.SilkS")
		)
		(fp_line
			(start 0.7874 -0.4064)
			(end -0.7874 -0.4064)
			(stroke
				(width 0.1524)
				(type default)
			)
			(layer "B.SilkS")
		)
		(fp_line
			(start 0.7874 0.4064)
			(end 0.7874 -0.4064)
			(stroke
				(width 0.1524)
				(type default)
			)
			(layer "B.SilkS")
		)
		(fp_line
			(start -0.67945 -0.3048)
			(end -0.67945 0.3048)
			(stroke
				(width 0.1)
				(type default)
			)
			(layer "B.Fab")
		)
		(fp_line
			(start -0.67945 0.3048)
			(end -0.120396 0.3048)
			(stroke
				(width 0.1)
				(type default)
			)
			(layer "B.Fab")
		)
		(fp_line
			(start -0.12065 -0.3048)
			(end -0.67945 -0.3048)
			(stroke
				(width 0.1)
				(type default)
			)
			(layer "B.Fab")
		)
		(fp_line
			(start -0.12065 -0.2794)
			(end -0.12065 -0.3048)
			(stroke
				(width 0.1)
				(type default)
			)
			(layer "B.Fab")
		)
		(fp_line
			(start -0.120396 0.2794)
			(end 0.12065 0.2794)
			(stroke
				(width 0.1)
				(type default)
			)
			(layer "B.Fab")
		)
		(fp_line
			(start -0.120396 0.3048)
			(end -0.120396 0.2794)
			(stroke
				(width 0.1)
				(type default)
			)
			(layer "B.Fab")
		)
		(fp_line
			(start 0.12065 -0.305054)
			(end 0.12065 -0.2794)
			(stroke
				(width 0.1)
				(type default)
			)
			(layer "B.Fab")
		)
		(fp_line
			(start 0.12065 -0.2794)
			(end -0.12065 -0.2794)
			(stroke
				(width 0.1)
				(type default)
			)
			(layer "B.Fab")
		)
		(fp_line
			(start 0.12065 0.2794)
			(end 0.12065 0.3048)
			(stroke
				(width 0.1)
				(type default)
			)
			(layer "B.Fab")
		)
		(fp_line
			(start 0.12065 0.3048)
			(end 0.67945 0.3048)
			(stroke
				(width 0.1)
				(type default)
			)
			(layer "B.Fab")
		)
		(fp_line
			(start 0.67945 -0.305054)
			(end 0.12065 -0.305054)
			(stroke
				(width 0.1)
				(type default)
			)
			(layer "B.Fab")
		)
		(fp_line
			(start 0.67945 0.3048)
			(end 0.67945 -0.305054)
			(stroke
				(width 0.1)
				(type default)
			)
			(layer "B.Fab")
		)
		(pad "1" smd circle
			(at 0.40005 0 180)
			(size 0 0)
			(layers "B.Cu" "B.Mask" "B.Paste")
			(net "P3V3_ADC128_2_VCC")
		)
		(pad "2" smd circle
			(at -0.40005 0 180)
			(size 0 0)
			(layers "B.Cu" "B.Mask" "B.Paste")
			(net "GND")
		)
	)
)
